# BARRELEYE-G2-SXM2 RISER BOARD-EVT-X00-BOM-X01-20171102_Final.xls.xlsx — Changelist (bom)
| BOM Change List Date:Tue Oct 17 11:23:26 GMT+08:00 2017 |  |  |  |  |  |  |  |  |  |
| New BOM file : E:\barreleye g2\1016\SXM2 RISER BOARD 1017.xls |  |  |  |  |  |  |  |  |  |
| Old BOM file : E:\barreleye g2\1016\SXM2 RISER BOARD 0825.xls |  |  |  |  |  |  |  |  |  |
| ##### Add Parts |  |  |  |  |  |  |  |  |  |
| Item | Location | Qty | Foxconn P/N | Part Description | Manufacturer Full Name | Manufacturer P/N | RoHS | Sheet |  |
| ##### Remove Parts |  |  |  |  |  |  |  |  |  |
| Item | Location | Qty | Foxconn P/N | Part Description | Manufacturer Full Name | Manufacturer P/N | RoHS | Sheet |  |
| 1 | R1594,R1595,R1596,R1598,R1620,R1621 | 6 | 610107A00-017-G | RES,0 Ohm,+/-5%,1/16W,G,SMD0402 | KOA SPEER ELECTRONICS, INC. | RK73Z1ETTP | G | PWA BOM |  |
|  |  |  | 610107A00-012-G | RES,0 Ohm,+/-5%,1/16W,G,SMD0402 | WALSIN TECHNOLOGY CORPORATION | WR04X000PTL | G | PWA BOM |  |
|  |  |  | 610107A00-011-G | RES,0 Ohm,+/-5%,1/16W,G,SMD0402 | YAGEO CORPORATION COMPONENT | RC0402JR-070RL | G | PWA BOM |  |
|  |  |  | 610107A00-044-G | RES,0 Ohm,+/-5%,1/16W,G,SMD0402 | TA-I TECHNOLOGY CO., LTD | RM04JTN0 | G | PWA BOM |  |
|  |  |  | 610107A00-024-G | RES,0 Ohm,+/-5%,1/16W,G,SMD0402 | PANASONIC INDUSTRIAL CO.,LTD. | ERJ2GE0R00X | G | PWA BOM |  |
|  |  |  | 610107A00-029-G | RES,0 Ohm,+/-5%,1/16W,G,SMD0402 | VISHAY ENTER TECHNO LOGY.INC | CRCW04020000Z0ED | G | PWA BOM |  |
| ##### Change Parts |  |  |  |  |  |  |  |  |  |
| Item | Location | Qty | Foxconn P/N | Part Description | Manufacturer Full Name | Manufacturer P/N | RoHS | Sheet | Remark |
| ##### Change Revision |  |  |  |  |  |  |  |  |  |
| Sheet | REV OF BOM | CUSTOMER | CUSTOMER P/N | PWA PN | PWA DESCRIPTION | PWA REV | DATE | Remark |  |
| OOOOOOOOOOOOOOOOOOOOOOOOOOOOOOOOOOOOOOOOOOOOOOOOOOOOOOOOOOOOOOOOOOOOOOOOOOOOOOOOOOOOOOOOOO | OOOOOOOOOOOOOOOOOOOOOOOOOOOOOOOOOOOOOOOOOOOOOOOOOOOOOOOOOOOOOOOOOOOOOOOOOOOOOOOOOOOOOOOOOO | OOOOOOOOOOOOOOOOOOOOOOOOOOOOOOOOOOOOOOOOOOOOOOOOOOOOOOOOOOOOOOOOOOOOOOOOOOOOOOOOOOOOOOOOOO | OOOOOOOOOOOOOOOOOOOOOOOOOOOOOOOOOOOOOOOOOOOOOOOOOOOOOOOOOOOOOOOOOOOOOOOOOOOOOOOOOOOOOOOOOO | OOOOOOOOOOOOOOOOOOOOOOOOOOOOOOOOOOOOOOOOOOOOOOOOOOOOOOOOOOOOOOOOOOOOOOOOOOOOOOOOOOOOOOOOOO | OOOOOOOOOOOOOOOOOOOOOOOOOOOOOOOOOOOOOOOOOOOOOOOOOOOOOOOOOOOOOOOOOOOOOOOOOOOOOOOOOOOOOOOOOO | OOOOOOOOOOOOOOOOOOOOOOOOOOOOOOOOOOOOOOOOOOOOOOOOOOOOOOOOOOOOOOOOOOOOOOOOOOOOOOOOOOOOOOOOOO | OOOOOOOOOOOOOOOOOOOOOOOOOOOOOOOOOOOOOOOOOOOOOOOOOOOOOOOOOOOOOOOOOOOOOOOOOOOOOOOOOOOOOOOOOO | OOOOOOOOOOOOOOOOOOOOOOOOOOOOOOOOOOOOOOOOOOOOOOOOOOOOOOOOOOOOOOOOOOOOOOOOOOOOOOOOOOOOOOOOOO | OOOOOOOOOOOOOOOOOOOOOOOOOOOOOOOOOOOOOOOOOOOOOOOOOOOOOOOOOOOOOOOOOOOOOOOOOOOOOOOOOOOOOOOOOO |
| Second Source Change |  |  |  |  |  |  |  |  |  |
| Item | Location | Change Type | Foxconn P/N | Part Description | Manufacturer Full Name | Manufacturer P/N | RoHS | Sheet |  |
| OOOOOOOOOOOOOOOOOOOOOOOOOOOOOOOOOOOOOOOOOOOOOOOOOOOOOOOOOOOOOOOOOOOOOOOOOOOOOOOOOOOOOOOOOO | OOOOOOOOOOOOOOOOOOOOOOOOOOOOOOOOOOOOOOOOOOOOOOOOOOOOOOOOOOOOOOOOOOOOOOOOOOOOOOOOOOOOOOOOOO | OOOOOOOOOOOOOOOOOOOOOOOOOOOOOOOOOOOOOOOOOOOOOOOOOOOOOOOOOOOOOOOOOOOOOOOOOOOOOOOOOOOOOOOOOO | OOOOOOOOOOOOOOOOOOOOOOOOOOOOOOOOOOOOOOOOOOOOOOOOOOOOOOOOOOOOOOOOOOOOOOOOOOOOOOOOOOOOOOOOOO | OOOOOOOOOOOOOOOOOOOOOOOOOOOOOOOOOOOOOOOOOOOOOOOOOOOOOOOOOOOOOOOOOOOOOOOOOOOOOOOOOOOOOOOOOO | OOOOOOOOOOOOOOOOOOOOOOOOOOOOOOOOOOOOOOOOOOOOOOOOOOOOOOOOOOOOOOOOOOOOOOOOOOOOOOOOOOOOOOOOOO | OOOOOOOOOOOOOOOOOOOOOOOOOOOOOOOOOOOOOOOOOOOOOOOOOOOOOOOOOOOOOOOOOOOOOOOOOOOOOOOOOOOOOOOOOO | OOOOOOOOOOOOOOOOOOOOOOOOOOOOOOOOOOOOOOOOOOOOOOOOOOOOOOOOOOOOOOOOOOOOOOOOOOOOOOOOOOOOOOOOOO | OOOOOOOOOOOOOOOOOOOOOOOOOOOOOOOOOOOOOOOOOOOOOOOOOOOOOOOOOOOOOOOOOOOOOOOOOOOOOOOOOOOOOOOOOO | OOOOOOOOOOOOOOOOOOOOOOOOOOOOOOOOOOOOOOOOOOOOOOOOOOOOOOOOOOOOOOOOOOOOOOOOOOOOOOOOOOOOOOOOOO |
| Master Materials Change |  |  |  |  |  |  |  |  |  |
| Item | Foxconn P/N | Orig._Usage | New_Usage | Part Description | Manufacturer Full Name | Manufacturer P/N | RoHS | Location | Sheet |
| 1 | 610107A00-017-G | 55 | 49 | RES,0 Ohm,+/-5%,1/16W,G,SMD0402 | KOA SPEER ELECTRONICS, INC. | RK73Z1ETTP | G | (-)R1594,R1595,R1596,R1598,R1620,R1621 | PWA BOM |
|  | 610107A00-012-G |  |  | RES,0 Ohm,+/-5%,1/16W,G,SMD0402 | WALSIN TECHNOLOGY CORPORATION | WR04X000PTL |  |  | PWA BOM |
|  | 610107A00-011-G |  |  | RES,0 Ohm,+/-5%,1/16W,G,SMD0402 | YAGEO CORPORATION COMPONENT | RC0402JR-070RL |  |  | PWA BOM |
|  | 610107A00-044-G |  |  | RES,0 Ohm,+/-5%,1/16W,G,SMD0402 | TA-I TECHNOLOGY CO., LTD | RM04JTN0 |  |  | PWA BOM |
|  | 610107A00-024-G |  |  | RES,0 Ohm,+/-5%,1/16W,G,SMD0402 | PANASONIC INDUSTRIAL CO.,LTD. | ERJ2GE0R00X |  |  | PWA BOM |
|  | 610107A00-029-G |  |  | RES,0 Ohm,+/-5%,1/16W,G,SMD0402 | VISHAY ENTER TECHNO LOGY.INC | CRCW04020000Z0ED |  |  | PWA BOM |
| OOOOOOOOOOOOOOOOOOOOOOOOOOOOOOOOOOOOOOOOOOOOOOOOOOOOOOOOOOOOOOOOOOOOOOOOOOOOOOOOOOOOOOOOOO | OOOOOOOOOOOOOOOOOOOOOOOOOOOOOOOOOOOOOOOOOOOOOOOOOOOOOOOOOOOOOOOOOOOOOOOOOOOOOOOOOOOOOOOOOO | OOOOOOOOOOOOOOOOOOOOOOOOOOOOOOOOOOOOOOOOOOOOOOOOOOOOOOOOOOOOOOOOOOOOOOOOOOOOOOOOOOOOOOOOOO | OOOOOOOOOOOOOOOOOOOOOOOOOOOOOOOOOOOOOOOOOOOOOOOOOOOOOOOOOOOOOOOOOOOOOOOOOOOOOOOOOOOOOOOOOO | OOOOOOOOOOOOOOOOOOOOOOOOOOOOOOOOOOOOOOOOOOOOOOOOOOOOOOOOOOOOOOOOOOOOOOOOOOOOOOOOOOOOOOOOOO | OOOOOOOOOOOOOOOOOOOOOOOOOOOOOOOOOOOOOOOOOOOOOOOOOOOOOOOOOOOOOOOOOOOOOOOOOOOOOOOOOOOOOOOOOO | OOOOOOOOOOOOOOOOOOOOOOOOOOOOOOOOOOOOOOOOOOOOOOOOOOOOOOOOOOOOOOOOOOOOOOOOOOOOOOOOOOOOOOOOOO | OOOOOOOOOOOOOOOOOOOOOOOOOOOOOOOOOOOOOOOOOOOOOOOOOOOOOOOOOOOOOOOOOOOOOOOOOOOOOOOOOOOOOOOOOO | OOOOOOOOOOOOOOOOOOOOOOOOOOOOOOOOOOOOOOOOOOOOOOOOOOOOOOOOOOOOOOOOOOOOOOOOOOOOOOOOOOOOOOOOOO |  |
| TLA Parts Change |  |  |  |  |  |  |  |  |  |
| Item | Foxconn P/N | Qty | Part Description | Manufacturer Full Name | Manufacturer P/N | RoHS | Location | Remark |  |
